# S9S_MB_2U (Grand Teton) — schematic netlist excerpt (pin names and nets, part order shuffled) for the footprints in the layout excerpt that follows; sources: Cadence DE-HDL packaged netlist, KiCad conversion of 03242023_DA0F0TMBIJ0_F0T_Motherboard_J_brd_V01_OCP.brd

R4553  Q_RES  4.7K 5% CHIP  pkg 0402LF  page 246 : A = P3V3_AUX ; B = HPDB_HSC_PWRGD_N
PC276_P0_4  Q_CAP  1UF 16V 10% X6S  pkg C0402  page 268 : A = SW_P12V_PVCCIN_CPU0_FLT ; B = GND

(kicad_pcb
	(version 20260206)
	(generator "pcbnew")
	(generator_version "10.0")
	(general
		(thickness 1.6)
		(legacy_teardrops no)
	)
	(paper "A4")
	(title_block
		(title "03242023_DA0F0TMBIJ0_F0T_Motherboard_J_brd_V01_OCP.brd")
		(comment 1 "Grand Teton / footprints 2244-2245 of 6105")
	)
	(layers
		(0 "F.Cu" signal "TOP")
		(4 "In1.Cu" signal "GND")
		(6 "In2.Cu" signal "IN1")
		(8 "In3.Cu" signal "GND1")
		(10 "In4.Cu" signal "IN2")
		(12 "In5.Cu" signal "GND2")
		(14 "In6.Cu" signal "IN3")
		(16 "In7.Cu" signal "GND3")
		(18 "In8.Cu" signal "VCC")
		(20 "In9.Cu" signal "VCC1")
		(22 "In10.Cu" signal "GND4")
		(24 "In11.Cu" signal "IN4")
		(26 "In12.Cu" signal "GND5")
		(28 "In13.Cu" signal "IN5")
		(30 "In14.Cu" signal "GND6")
		(32 "In15.Cu" signal "IN6")
		(34 "In16.Cu" signal "GND7")
		(2 "B.Cu" signal "BOTTOM")
		(9 "F.Adhes" user "F.Adhesive")
		(11 "B.Adhes" user "B.Adhesive")
		(13 "F.Paste" user "Package Geometry/Pastemask Top")
		(15 "B.Paste" user "Package Geometry/Pastemask Bottom")
		(5 "F.SilkS" user "Ref Des/Silkscreen Top")
		(7 "B.SilkS" user "Ref Des/Silkscreen Bottom")
		(1 "F.Mask" user "Board Geometry/Soldermask Top")
		(3 "B.Mask" user "Board Geometry/Soldermask Bottom")
		(17 "Dwgs.User" user "User.Drawings")
		(19 "Cmts.User" user "User.Comments")
		(21 "Eco1.User" user "User.Eco1")
		(23 "Eco2.User" user "User.Eco2")
		(25 "Edge.Cuts" user "Board Geometry/Outline")
		(27 "Margin" user)
		(31 "F.CrtYd" user "Package Geometry/Place Bound Top")
		(29 "B.CrtYd" user "Package Geometry/Place Bound Bottom")
		(35 "F.Fab" user "Ref Des/Assembly Top")
		(33 "B.Fab" user "Ref Des/Assembly Bottom")
	)
	(footprint ""
		(layer "F.Cu")
		(at 372.988332 -333.804514 -90)
		(property "Reference" "PC276_P0_4"
			(at 0 0 270)
			(layer "F.SilkS")
			(hide yes)
			(effects
				(font
					(size 1.27 1.27)
				)
			)
		)
		(property "Value" ""
			(at 0 0 270)
			(layer "F.Fab")
			(effects
				(font
					(size 1.27 1.27)
				)
			)
		)
		(duplicate_pad_numbers_are_jumpers no)
		(fp_line
			(start -0.7874 0.4064)
			(end -0.7874 -0.4064)
			(stroke
				(width 0.1524)
				(type default)
			)
			(layer "F.SilkS")
		)
		(fp_line
			(start 0.7874 0.4064)
			(end -0.7874 0.4064)
			(stroke
				(width 0.1524)
				(type default)
			)
			(layer "F.SilkS")
		)
		(fp_line
			(start -0.7874 -0.4064)
			(end 0.7874 -0.4064)
			(stroke
				(width 0.1524)
				(type default)
			)
			(layer "F.SilkS")
		)
		(fp_line
			(start 0.7874 -0.4064)
			(end 0.7874 0.4064)
			(stroke
				(width 0.1524)
				(type default)
			)
			(layer "F.SilkS")
		)
		(fp_line
			(start -0.67945 0.3048)
			(end -0.67945 -0.305054)
			(stroke
				(width 0.1)
				(type default)
			)
			(layer "F.Fab")
		)
		(fp_line
			(start -0.12065 0.3048)
			(end -0.67945 0.3048)
			(stroke
				(width 0.1)
				(type default)
			)
			(layer "F.Fab")
		)
		(fp_line
			(start 0.120396 0.3048)
			(end 0.120396 0.2794)
			(stroke
				(width 0.1)
				(type default)
			)
			(layer "F.Fab")
		)
		(fp_line
			(start 0.67945 0.3048)
			(end 0.120396 0.3048)
			(stroke
				(width 0.1)
				(type default)
			)
			(layer "F.Fab")
		)
		(fp_line
			(start -0.12065 0.2794)
			(end -0.12065 0.3048)
			(stroke
				(width 0.1)
				(type default)
			)
			(layer "F.Fab")
		)
		(fp_line
			(start 0.120396 0.2794)
			(end -0.12065 0.2794)
			(stroke
				(width 0.1)
				(type default)
			)
			(layer "F.Fab")
		)
		(fp_line
			(start -0.12065 -0.2794)
			(end 0.12065 -0.2794)
			(stroke
				(width 0.1)
				(type default)
			)
			(layer "F.Fab")
		)
		(fp_line
			(start 0.12065 -0.2794)
			(end 0.12065 -0.3048)
			(stroke
				(width 0.1)
				(type default)
			)
			(layer "F.Fab")
		)
		(fp_line
			(start 0.12065 -0.3048)
			(end 0.67945 -0.3048)
			(stroke
				(width 0.1)
				(type default)
			)
			(layer "F.Fab")
		)
		(fp_line
			(start 0.67945 -0.3048)
			(end 0.67945 0.3048)
			(stroke
				(width 0.1)
				(type default)
			)
			(layer "F.Fab")
		)
		(fp_line
			(start -0.67945 -0.305054)
			(end -0.12065 -0.305054)
			(stroke
				(width 0.1)
				(type default)
			)
			(layer "F.Fab")
		)
		(fp_line
			(start -0.12065 -0.305054)
			(end -0.12065 -0.2794)
			(stroke
				(width 0.1)
				(type default)
			)
			(layer "F.Fab")
		)
		(pad "1" smd circle
			(at -0.40005 0 270)
			(size 0 0)
			(layers "F.Cu" "F.Mask" "F.Paste")
			(net "SW_P12V_PVCCIN_CPU0_FLT")
		)
		(pad "2" smd circle
			(at 0.40005 0 270)
			(size 0 0)
			(layers "F.Cu" "F.Mask" "F.Paste")
			(net "GND")
		)
	)
	(footprint ""
		(layer "F.Cu")
		(at 292.273228 -413.07512 180)
		(property "Reference" "R4553"
			(at 0 0 180)
			(layer "F.SilkS")
			(hide yes)
			(effects
				(font
					(size 1.27 1.27)
				)
			)
		)
		(property "Value" ""
			(at 0 0 180)
			(layer "F.Fab")
			(effects
				(font
					(size 1.27 1.27)
				)
			)
		)
		(duplicate_pad_numbers_are_jumpers no)
		(fp_line
			(start 0.7874 0.4064)
			(end -0.7874 0.4064)
			(stroke
				(width 0.1524)
				(type default)
			)
			(layer "F.SilkS")
		)
		(fp_line
			(start 0.7874 -0.4064)
			(end 0.7874 0.4064)
			(stroke
				(width 0.1524)
				(type default)
			)
			(layer "F.SilkS")
		)
		(fp_line
			(start -0.7874 0.4064)
			(end -0.7874 -0.4064)
			(stroke
				(width 0.1524)
				(type default)
			)
			(layer "F.SilkS")
		)
		(fp_line
			(start -0.7874 -0.4064)
			(end 0.7874 -0.4064)
			(stroke
				(width 0.1524)
				(type default)
			)
			(layer "F.SilkS")
		)
		(fp_line
			(start 0.67945 0.3048)
			(end 0.120396 0.3048)
			(stroke
				(width 0.1)
				(type default)
			)
			(layer "F.Fab")
		)
		(fp_line
			(start 0.67945 -0.3048)
			(end 0.67945 0.3048)
			(stroke
				(width 0.1)
				(type default)
			)
			(layer "F.Fab")
		)
		(fp_line
			(start 0.12065 -0.2794)
			(end 0.12065 -0.3048)
			(stroke
				(width 0.1)
				(type default)
			)
			(layer "F.Fab")
		)
		(fp_line
			(start 0.12065 -0.3048)
			(end 0.67945 -0.3048)
			(stroke
				(width 0.1)
				(type default)
			)
			(layer "F.Fab")
		)
		(fp_line
			(start 0.120396 0.3048)
			(end 0.120396 0.2794)
			(stroke
				(width 0.1)
				(type default)
			)
			(layer "F.Fab")
		)
		(fp_line
			(start 0.120396 0.2794)
			(end -0.12065 0.2794)
			(stroke
				(width 0.1)
				(type default)
			)
			(layer "F.Fab")
		)
		(fp_line
			(start -0.12065 0.3048)
			(end -0.67945 0.3048)
			(stroke
				(width 0.1)
				(type default)
			)
			(layer "F.Fab")
		)
		(fp_line
			(start -0.12065 0.2794)
			(end -0.12065 0.3048)
			(stroke
				(width 0.1)
				(type default)
			)
			(layer "F.Fab")
		)
		(fp_line
			(start -0.12065 -0.2794)
			(end 0.12065 -0.2794)
			(stroke
				(width 0.1)
				(type default)
			)
			(layer "F.Fab")
		)
		(fp_line
			(start -0.12065 -0.305054)
			(end -0.12065 -0.2794)
			(stroke
				(width 0.1)
				(type default)
			)
			(layer "F.Fab")
		)
		(fp_line
			(start -0.67945 0.3048)
			(end -0.67945 -0.305054)
			(stroke
				(width 0.1)
				(type default)
			)
			(layer "F.Fab")
		)
		(fp_line
			(start -0.67945 -0.305054)
			(end -0.12065 -0.305054)
			(stroke
				(width 0.1)
				(type default)
			)
			(layer "F.Fab")
		)
		(pad "1" smd circle
			(at -0.40005 0 180)
			(size 0 0)
			(layers "F.Cu" "F.Mask" "F.Paste")
			(net "P3V3_AUX")
		)
		(pad "2" smd circle
			(at 0.40005 0 180)
			(size 0 0)
			(layers "F.Cu" "F.Mask" "F.Paste")
			(net "HPDB_HSC_PWRGD_N")
		)
	)
)
